# TIMECARD (Time Appliance Project (Time Card)) — schematic netlist excerpt (pin names and nets, part order shuffled) for the footprints in the layout excerpt that follows; sources: Cadence DE-HDL packaged netlist, KiCad conversion of R4006-B0001-02_R01.brd

R302  RESISTOR  1KOHM 1%  pkg SMC_0402R_H016  page 20 : \1\ = BNO080_SA0 ; \2\ = SG
SP24  SOLDER_PREFORM  pkg 0201_SOLDER_PREFORM_4MIL  page 34 : \1\ = NC ; \2\ = NC
R254  RESISTOR  20OHM 1%  pkg SMC_0402R_H016  page 29 : \1\ = XP1R0V_FPGA ; \2\ = UNNAMED_523_CAPACITOR_I28_1

(kicad_pcb
	(version 20260206)
	(generator "pcbnew")
	(generator_version "10.0")
	(general
		(thickness 1.6)
		(legacy_teardrops no)
	)
	(paper "A4")
	(title_block
		(title "timecard-production-celestica-r4006 — R4006-B0001-02_R01.brd")
		(comment 1 "Time Appliance Project (Time Card) / footprints 634-636 of 1113")
	)
	(layers
		(0 "F.Cu" signal "TOP")
		(4 "In1.Cu" signal "L02_GND1")
		(6 "In2.Cu" signal "L03_SIG1")
		(8 "In3.Cu" signal "L04_GND2")
		(10 "In4.Cu" signal "L05_VCC1")
		(12 "In5.Cu" signal "L06_VCC2")
		(14 "In6.Cu" signal "L07_GND3")
		(16 "In7.Cu" signal "L08_SIG2")
		(18 "In8.Cu" signal "L09_GND4")
		(2 "B.Cu" signal "BOTTOM")
		(9 "F.Adhes" user "F.Adhesive")
		(11 "B.Adhes" user "B.Adhesive")
		(13 "F.Paste" user "Package Geometry/Pastemask Top")
		(15 "B.Paste" user "Package Geometry/Pastemask Bottom")
		(5 "F.SilkS" user "Ref Des/Silkscreen Top")
		(7 "B.SilkS" user "Ref Des/Silkscreen Bottom")
		(1 "F.Mask" user "Board Geometry/Soldermask Top")
		(3 "B.Mask" user "Board Geometry/Soldermask Bottom")
		(17 "Dwgs.User" user "User.Drawings")
		(19 "Cmts.User" user "User.Comments")
		(21 "Eco1.User" user "User.Eco1")
		(23 "Eco2.User" user "User.Eco2")
		(25 "Edge.Cuts" user "Board Geometry/Outline")
		(27 "Margin" user)
		(31 "F.CrtYd" user "Package Geometry/Place Bound Top")
		(29 "B.CrtYd" user "Package Geometry/Place Bound Bottom")
		(35 "F.Fab" user "Ref Des/Assembly Top")
		(33 "B.Fab" user "Ref Des/Assembly Bottom")
	)
	(footprint ""
		(layer "F.Cu")
		(at 144.145 -60.96)
		(property "Reference" "R254"
			(at -2.286 -3.51663 0)
			(unlocked yes)
			(layer "F.SilkS")
			(effects
				(font
					(size 0.7874 0.5842)
					(thickness 0.1524)
				)
			)
		)
		(property "Value" "VAL*"
			(at 0.02032 2.13233 0)
			(unlocked yes)
			(layer "F.Fab")
			(hide yes)
			(effects
				(font
					(size 0.7874 0.5842)
					(thickness 0.1524)
				)
			)
		)
		(property "Device Type" "RESISTOR-G155-120R0-01,20OHM,1%"
			(at 0.008382 1.210564 0)
			(unlocked yes)
			(layer "F.Fab")
			(hide yes)
			(effects
				(font
					(size 0.7874 0.5842)
					(thickness 0.1524)
				)
			)
		)
		(property "User Part Number" "PARTNUM*"
			(at 0.02032 4.024884 0)
			(unlocked yes)
			(layer "Cmts.User")
			(hide yes)
			(effects
				(font
					(size 0.7874 0.5842)
					(thickness 0.1524)
				)
			)
		)
		(property "Tolerance" "TOL*"
			(at 0.044704 3.05435 0)
			(unlocked yes)
			(layer "Cmts.User")
			(hide yes)
			(effects
				(font
					(size 0.7874 0.5842)
					(thickness 0.1524)
				)
			)
		)
		(duplicate_pad_numbers_are_jumpers no)
		(fp_line
			(start -1.143 -0.5588)
			(end -1.143 0.5588)
			(stroke
				(width 0.1)
				(type default)
			)
			(layer "F.SilkS")
		)
		(fp_line
			(start -1.143 0.5588)
			(end 1.143 0.5588)
			(stroke
				(width 0.1)
				(type default)
			)
			(layer "F.SilkS")
		)
		(fp_line
			(start 1.143 -0.5588)
			(end -1.143 -0.5588)
			(stroke
				(width 0.1)
				(type default)
			)
			(layer "F.SilkS")
		)
		(fp_line
			(start 1.143 0.5588)
			(end 1.143 -0.5588)
			(stroke
				(width 0.1)
				(type default)
			)
			(layer "F.SilkS")
		)
		(fp_rect
			(start 1.143 -0.5588)
			(end -1.143 0.5588)
			(stroke
				(width 0)
				(type default)
			)
			(fill no)
			(layer "F.CrtYd")
		)
		(fp_line
			(start -0.508 -0.3048)
			(end -0.508 0.3048)
			(stroke
				(width 0.1)
				(type default)
			)
			(layer "F.Fab")
		)
		(fp_line
			(start -0.508 0.3048)
			(end 0.508 0.3048)
			(stroke
				(width 0.1)
				(type default)
			)
			(layer "F.Fab")
		)
		(fp_line
			(start 0.508 -0.3048)
			(end -0.508 -0.3048)
			(stroke
				(width 0.1)
				(type default)
			)
			(layer "F.Fab")
		)
		(fp_line
			(start 0.508 0.3048)
			(end 0.508 -0.3048)
			(stroke
				(width 0.1)
				(type default)
			)
			(layer "F.Fab")
		)
		(pad "1" smd rect
			(at -0.5334 0)
			(size 0.7112 0.6096)
			(layers "F.Cu" "F.Mask" "F.Paste")
			(net "XP1R0V_FPGA")
		)
		(pad "2" smd rect
			(at 0.5334 0)
			(size 0.7112 0.6096)
			(layers "F.Cu" "F.Mask" "F.Paste")
			(net "UNNAMED_523_CAPACITOR_I28_1")
		)
		(zone
			(layer "F.Cu")
			(hatch none 0.5)
			(connect_pads
				(clearance 0)
			)
			(min_thickness 0.25)
			(keepout
				(tracks allowed)
				(vias not_allowed)
				(pads allowed)
				(copperpour not_allowed)
				(footprints allowed)
			)
			(placement
				(enabled no)
				(sheetname "")
			)
			(fill
				(thermal_gap 0.5)
				(thermal_bridge_width 0.5)
				(island_removal_mode 0)
			)
			(polygon
				(pts
					(xy 144.2212 -61.2648) (xy 144.0688 -61.2648) (xy 144.0688 -60.6552) (xy 144.2212 -60.6552)
				)
			)
		)
	)
	(footprint ""
		(layer "F.Cu")
		(at 80.772 -54.9656 180)
		(property "Reference" "R302"
			(at 10.16 18.78203 0)
			(unlocked yes)
			(layer "F.SilkS")
			(effects
				(font
					(size 0.7874 0.5842)
					(thickness 0.1524)
				)
			)
		)
		(property "Value" "VAL*"
			(at 0.02032 2.13233 180)
			(unlocked yes)
			(layer "F.Fab")
			(hide yes)
			(effects
				(font
					(size 0.7874 0.5842)
					(thickness 0.1524)
				)
			)
		)
		(property "Tolerance" "TOL*"
			(at 0.044704 3.05435 180)
			(unlocked yes)
			(layer "Cmts.User")
			(hide yes)
			(effects
				(font
					(size 0.7874 0.5842)
					(thickness 0.1524)
				)
			)
		)
		(property "User Part Number" "PARTNUM*"
			(at 0.02032 4.024884 180)
			(unlocked yes)
			(layer "Cmts.User")
			(hide yes)
			(effects
				(font
					(size 0.7874 0.5842)
					(thickness 0.1524)
				)
			)
		)
		(property "Device Type" "RESISTOR-G155-11001-01,1KOHM,1%"
			(at 0.008382 1.210564 180)
			(unlocked yes)
			(layer "F.Fab")
			(hide yes)
			(effects
				(font
					(size 0.7874 0.5842)
					(thickness 0.1524)
				)
			)
		)
		(duplicate_pad_numbers_are_jumpers no)
		(fp_line
			(start 1.143 0.5588)
			(end 1.143 -0.5588)
			(stroke
				(width 0.1)
				(type default)
			)
			(layer "F.SilkS")
		)
		(fp_line
			(start 1.143 -0.5588)
			(end -1.143 -0.5588)
			(stroke
				(width 0.1)
				(type default)
			)
			(layer "F.SilkS")
		)
		(fp_line
			(start -1.143 0.5588)
			(end 1.143 0.5588)
			(stroke
				(width 0.1)
				(type default)
			)
			(layer "F.SilkS")
		)
		(fp_line
			(start -1.143 -0.5588)
			(end -1.143 0.5588)
			(stroke
				(width 0.1)
				(type default)
			)
			(layer "F.SilkS")
		)
		(fp_rect
			(start 1.143 0.5588)
			(end -1.143 -0.5588)
			(stroke
				(width 0)
				(type default)
			)
			(fill no)
			(layer "F.CrtYd")
		)
		(fp_line
			(start 0.508 0.3048)
			(end 0.508 -0.3048)
			(stroke
				(width 0.1)
				(type default)
			)
			(layer "F.Fab")
		)
		(fp_line
			(start 0.508 -0.3048)
			(end -0.508 -0.3048)
			(stroke
				(width 0.1)
				(type default)
			)
			(layer "F.Fab")
		)
		(fp_line
			(start -0.508 0.3048)
			(end 0.508 0.3048)
			(stroke
				(width 0.1)
				(type default)
			)
			(layer "F.Fab")
		)
		(fp_line
			(start -0.508 -0.3048)
			(end -0.508 0.3048)
			(stroke
				(width 0.1)
				(type default)
			)
			(layer "F.Fab")
		)
		(pad "1" smd rect
			(at -0.5334 0 180)
			(size 0.7112 0.6096)
			(layers "F.Cu" "F.Mask" "F.Paste")
			(net "BNO080_SA0")
		)
		(pad "2" smd rect
			(at 0.5334 0 180)
			(size 0.7112 0.6096)
			(layers "F.Cu" "F.Mask" "F.Paste")
			(net "SG")
		)
		(zone
			(layer "F.Cu")
			(hatch none 0.5)
			(connect_pads
				(clearance 0)
			)
			(min_thickness 0.25)
			(keepout
				(tracks allowed)
				(vias not_allowed)
				(pads allowed)
				(copperpour not_allowed)
				(footprints allowed)
			)
			(placement
				(enabled no)
				(sheetname "")
			)
			(fill
				(thermal_gap 0.5)
				(thermal_bridge_width 0.5)
				(island_removal_mode 0)
			)
			(polygon
				(pts
					(xy 80.6958 -55.2704) (xy 80.6958 -54.6608) (xy 80.8482 -54.6608) (xy 80.8482 -55.2704)
				)
			)
		)
	)
	(footprint ""
		(layer "F.Cu")
		(at 46.736 -123.825)
		(property "Reference" "SP24"
			(at 0 0 0)
			(layer "F.SilkS")
			(hide yes)
			(effects
				(font
					(size 1.27 1.27)
				)
			)
		)
		(property "Value" ""
			(at 0 0 0)
			(layer "F.Fab")
			(effects
				(font
					(size 1.27 1.27)
				)
			)
		)
		(duplicate_pad_numbers_are_jumpers no)
	)
)
